(kicad_pcb
	(version 20260206)
	(generator "pcbnew")
	(generator_version "10.0")
	(general
		(thickness 1.6)
		(legacy_teardrops no)
	)
	(paper "A4")
	(title_block
		(title "panther-plus-userver — 13130-1b_20150205.brd")
		(comment 1 "Honey Badger (Wiwynn) / footprint 894 of 1509 (DIMM1), pads 58-64 of 210")
	)
	(layers
		(0 "F.Cu" signal "TOP")
		(4 "In1.Cu" signal "L2")
		(6 "In2.Cu" signal "L3")
		(8 "In3.Cu" signal "L4")
		(10 "In4.Cu" signal "L5")
		(12 "In5.Cu" signal "L6")
		(14 "In6.Cu" signal "L7")
		(16 "In7.Cu" signal "L8")
		(18 "In8.Cu" signal "L9")
		(20 "In9.Cu" signal "L10")
		(22 "In10.Cu" signal "L11")
		(2 "B.Cu" signal "BOTTOM")
		(9 "F.Adhes" user "F.Adhesive")
		(11 "B.Adhes" user "B.Adhesive")
		(13 "F.Paste" user "Package Geometry/Pastemask Top")
		(15 "B.Paste" user "Package Geometry/Pastemask Bottom")
		(5 "F.SilkS" user "Ref Des/Silkscreen Top")
		(7 "B.SilkS" user "Ref Des/Silkscreen Bottom")
		(1 "F.Mask" user "Board Geometry/Soldermask Top")
		(3 "B.Mask" user "Board Geometry/Soldermask Bottom")
		(17 "Dwgs.User" user "User.Drawings")
		(19 "Cmts.User" user "User.Comments")
		(21 "Eco1.User" user "User.Eco1")
		(23 "Eco2.User" user "User.Eco2")
		(25 "Edge.Cuts" user "Board Geometry/Outline")
		(27 "Margin" user)
		(31 "F.CrtYd" user "Package Geometry/Place Bound Top")
		(29 "B.CrtYd" user "Package Geometry/Place Bound Bottom")
		(35 "F.Fab" user "Ref Des/Assembly Top")
		(33 "B.Fab" user "Ref Des/Assembly Bottom")
	)
	(footprint ""
		(layer "B.Cu")
		(at 158.500064 -66.699892 180)
		(property "Reference" "DIMM1"
			(at 0 0 0)
			(layer "B.SilkS")
			(hide yes)
			(effects
				(font
					(size 1.27 1.27)
				)
				(justify mirror)
			)
		)
		(property "Value" "DDR3-204P-142-COLAY-1-GP-U"
			(at 41.312338 -16.676878 180)
			(unlocked yes)
			(layer "B.Fab")
			(hide yes)
			(effects
				(font
					(size 1.016 1.016)
					(thickness 0.1524)
				)
				(justify mirror)
			)
		)
		(property "Device Type" "AS0A626-J8R6-7H-COLAY-1"
			(at 41.312338 -18.200878 180)
			(unlocked yes)
			(layer "B.Fab")
			(hide yes)
			(effects
				(font
					(size 1.016 1.016)
					(thickness 0.1524)
				)
				(justify mirror)
			)
		)
		(duplicate_pad_numbers_are_jumpers no)
		(pad "56" smd custom
			(at -15.150084 4.100068)
			(size 0.1143 0.1143)
			(layers "B.Cu" "B.Mask" "B.Paste")
			(net "M_A_DQ29")
			(options
				(clearance outline)
				(anchor circle)
			)
			(primitives
				(gr_poly
					(pts
						(xy 0 -0.9017) (xy -0.03175 -0.89916) (xy -0.0635 -0.889) (xy -0.09144 -0.87376) (xy -0.11684 -0.85344)
						(xy -0.13716 -0.82804) (xy -0.1524 -0.8001) (xy -0.16256 -0.76835) (xy -0.1651 -0.7366) (xy -0.1651 -0.11938)
						(xy -0.17272 -0.11176) (xy -0.19812 -0.0762) (xy -0.2032 -0.06604) (xy -0.20701 -0.05715) (xy -0.21209 -0.04699)
						(xy -0.2159 -0.03683) (xy -0.21844 -0.02667) (xy -0.22225 -0.01524) (xy -0.22352 -0.00508) (xy -0.22606 0.00508)
						(xy -0.22733 0.01651) (xy -0.22733 0.02667) (xy -0.2286 0.0381) (xy -0.22733 0.04953) (xy -0.22733 0.05969)
						(xy -0.22606 0.07112) (xy -0.22352 0.08128) (xy -0.22225 0.09144) (xy -0.21844 0.10287) (xy -0.2159 0.11303)
						(xy -0.21209 0.12319) (xy -0.20701 0.13335) (xy -0.2032 0.14224) (xy -0.19812 0.1524) (xy -0.17272 0.18796)
						(xy -0.1651 0.19558) (xy -0.1651 0.7366) (xy -0.16256 0.76835) (xy -0.1524 0.8001) (xy -0.13716 0.82804)
						(xy -0.11684 0.85344) (xy -0.09144 0.87376) (xy -0.0635 0.889) (xy -0.03175 0.89916) (xy 0 0.9017)
						(xy 0.03175 0.89916) (xy 0.0635 0.889) (xy 0.09144 0.87376) (xy 0.11684 0.85344) (xy 0.13716 0.82804)
						(xy 0.1524 0.8001) (xy 0.16256 0.76835) (xy 0.1651 0.7366) (xy 0.1651 0.19685) (xy 0.17272 0.18923)
						(xy 0.17907 0.18034) (xy 0.18669 0.17145) (xy 0.19177 0.16256) (xy 0.19812 0.15367) (xy 0.20828 0.13335)
						(xy 0.21971 0.10287) (xy 0.22225 0.09271) (xy 0.22479 0.08128) (xy 0.22606 0.07112) (xy 0.2286 0.05969)
						(xy 0.2286 0.01651) (xy 0.22606 0.00508) (xy 0.22479 -0.00508) (xy 0.22225 -0.01651) (xy 0.21971 -0.02667)
						(xy 0.20828 -0.05715) (xy 0.19812 -0.07747) (xy 0.19177 -0.08636) (xy 0.18669 -0.09525) (xy 0.17907 -0.10414)
						(xy 0.17272 -0.11303) (xy 0.1651 -0.12065) (xy 0.1651 -0.7366) (xy 0.16256 -0.76835) (xy 0.1524 -0.8001)
						(xy 0.13716 -0.82804) (xy 0.11684 -0.85344) (xy 0.09144 -0.87376) (xy 0.0635 -0.889) (xy 0.03175 -0.89916)
					)
					(width 0)
					(fill yes)
				)
			)
		)
		(pad "57" smd custom
			(at -14.85011 -4.100068)
			(size 0.1143 0.1143)
			(layers "B.Cu" "B.Mask" "B.Paste")
			(net "M_A_DQ25")
			(options
				(clearance outline)
				(anchor circle)
			)
			(primitives
				(gr_poly
					(pts
						(xy 0 -0.9017) (xy -0.03175 -0.89916) (xy -0.0635 -0.889) (xy -0.09144 -0.87376) (xy -0.11684 -0.85344)
						(xy -0.13716 -0.82804) (xy -0.1524 -0.8001) (xy -0.16256 -0.76835) (xy -0.1651 -0.7366) (xy -0.1651 -0.44958)
						(xy -0.17272 -0.44196) (xy -0.19812 -0.4064) (xy -0.2032 -0.39624) (xy -0.20701 -0.38735) (xy -0.21209 -0.37719)
						(xy -0.2159 -0.36703) (xy -0.21844 -0.35687) (xy -0.22225 -0.34544) (xy -0.22352 -0.33528) (xy -0.22606 -0.32512)
						(xy -0.22733 -0.31369) (xy -0.22733 -0.30353) (xy -0.2286 -0.2921) (xy -0.22733 -0.28067) (xy -0.22733 -0.27051)
						(xy -0.22606 -0.25908) (xy -0.22352 -0.24892) (xy -0.22225 -0.23876) (xy -0.21844 -0.22733) (xy -0.2159 -0.21717)
						(xy -0.21209 -0.20701) (xy -0.20701 -0.19685) (xy -0.2032 -0.18796) (xy -0.19812 -0.1778) (xy -0.17272 -0.14224)
						(xy -0.1651 -0.13462) (xy -0.1651 0.7366) (xy -0.16256 0.76835) (xy -0.1524 0.8001) (xy -0.13716 0.82804)
						(xy -0.11684 0.85344) (xy -0.09144 0.87376) (xy -0.0635 0.889) (xy -0.03175 0.89916) (xy 0 0.9017)
						(xy 0.03175 0.89916) (xy 0.0635 0.889) (xy 0.09144 0.87376) (xy 0.11684 0.85344) (xy 0.13716 0.82804)
						(xy 0.1524 0.8001) (xy 0.16256 0.76835) (xy 0.1651 0.7366) (xy 0.1651 -0.13462) (xy 0.17272 -0.14224)
						(xy 0.19812 -0.1778) (xy 0.2032 -0.18796) (xy 0.20701 -0.19685) (xy 0.21209 -0.20701) (xy 0.2159 -0.21717)
						(xy 0.21844 -0.22733) (xy 0.22225 -0.23876) (xy 0.22352 -0.24892) (xy 0.22606 -0.25908) (xy 0.22733 -0.27051)
						(xy 0.22733 -0.28067) (xy 0.2286 -0.2921) (xy 0.22733 -0.30353) (xy 0.22733 -0.31369) (xy 0.22606 -0.32512)
						(xy 0.22352 -0.33528) (xy 0.22225 -0.34544) (xy 0.21844 -0.35687) (xy 0.2159 -0.36703) (xy 0.21209 -0.37719)
						(xy 0.20701 -0.38735) (xy 0.2032 -0.39624) (xy 0.19812 -0.4064) (xy 0.17272 -0.44196) (xy 0.1651 -0.44958)
						(xy 0.1651 -0.7366) (xy 0.16256 -0.76835) (xy 0.1524 -0.8001) (xy 0.13716 -0.82804) (xy 0.11684 -0.85344)
						(xy 0.09144 -0.87376) (xy 0.0635 -0.889) (xy 0.03175 -0.89916)
					)
					(width 0)
					(fill yes)
				)
			)
		)
		(pad "58" smd custom
			(at -14.549882 4.100068)
			(size 0.1143 0.1143)
			(layers "B.Cu" "B.Mask" "B.Paste")
			(net "GND")
			(options
				(clearance outline)
				(anchor circle)
			)
			(primitives
				(gr_poly
					(pts
						(xy 0 -0.9017) (xy -0.03175 -0.89916) (xy -0.0635 -0.889) (xy -0.09144 -0.87376) (xy -0.11684 -0.85344)
						(xy -0.13716 -0.82804) (xy -0.1524 -0.8001) (xy -0.16256 -0.76835) (xy -0.1651 -0.7366) (xy -0.1651 0.13462)
						(xy -0.17272 0.14224) (xy -0.19812 0.1778) (xy -0.2032 0.18796) (xy -0.20701 0.19685) (xy -0.21209 0.20701)
						(xy -0.2159 0.21717) (xy -0.21844 0.22733) (xy -0.22225 0.23876) (xy -0.22352 0.24892) (xy -0.22606 0.25908)
						(xy -0.22733 0.27051) (xy -0.22733 0.28067) (xy -0.2286 0.2921) (xy -0.22733 0.30353) (xy -0.22733 0.31369)
						(xy -0.22606 0.32512) (xy -0.22352 0.33528) (xy -0.22225 0.34544) (xy -0.21844 0.35687) (xy -0.2159 0.36703)
						(xy -0.21209 0.37719) (xy -0.20701 0.38735) (xy -0.2032 0.39624) (xy -0.19812 0.4064) (xy -0.17272 0.44196)
						(xy -0.1651 0.44958) (xy -0.1651 0.7366) (xy -0.16256 0.76835) (xy -0.1524 0.8001) (xy -0.13716 0.82804)
						(xy -0.11684 0.85344) (xy -0.09144 0.87376) (xy -0.0635 0.889) (xy -0.03175 0.89916) (xy 0 0.9017)
						(xy 0.03175 0.89916) (xy 0.0635 0.889) (xy 0.09144 0.87376) (xy 0.11684 0.85344) (xy 0.13716 0.82804)
						(xy 0.1524 0.8001) (xy 0.16256 0.76835) (xy 0.1651 0.7366) (xy 0.1651 0.44958) (xy 0.17272 0.44196)
						(xy 0.19812 0.4064) (xy 0.2032 0.39624) (xy 0.20701 0.38735) (xy 0.21209 0.37719) (xy 0.2159 0.36703)
						(xy 0.21844 0.35687) (xy 0.22225 0.34544) (xy 0.22352 0.33528) (xy 0.22606 0.32512) (xy 0.22733 0.31369)
						(xy 0.22733 0.30353) (xy 0.2286 0.2921) (xy 0.22733 0.28067) (xy 0.22733 0.27051) (xy 0.22606 0.25908)
						(xy 0.22352 0.24892) (xy 0.22225 0.23876) (xy 0.21844 0.22733) (xy 0.2159 0.21717) (xy 0.21209 0.20701)
						(xy 0.20701 0.19685) (xy 0.2032 0.18796) (xy 0.19812 0.1778) (xy 0.17272 0.14224) (xy 0.1651 0.13462)
						(xy 0.1651 -0.7366) (xy 0.16256 -0.76835) (xy 0.1524 -0.8001) (xy 0.13716 -0.82804) (xy 0.11684 -0.85344)
						(xy 0.09144 -0.87376) (xy 0.0635 -0.889) (xy 0.03175 -0.89916)
					)
					(width 0)
					(fill yes)
				)
			)
		)
		(pad "59" smd custom
			(at -14.249908 -4.100068)
			(size 0.1143 0.1143)
			(layers "B.Cu" "B.Mask" "B.Paste")
			(net "GND")
			(options
				(clearance outline)
				(anchor circle)
			)
			(primitives
				(gr_poly
					(pts
						(xy 0 -0.9017) (xy -0.03175 -0.89916) (xy -0.0635 -0.889) (xy -0.09144 -0.87376) (xy -0.11684 -0.85344)
						(xy -0.13716 -0.82804) (xy -0.1524 -0.8001) (xy -0.16256 -0.76835) (xy -0.1651 -0.7366) (xy -0.1651 -0.19685)
						(xy -0.17272 -0.18923) (xy -0.17907 -0.18034) (xy -0.18669 -0.17145) (xy -0.19177 -0.16256) (xy -0.19812 -0.15367)
						(xy -0.20828 -0.13335) (xy -0.21971 -0.10287) (xy -0.22225 -0.09271) (xy -0.22479 -0.08128) (xy -0.22606 -0.07112)
						(xy -0.2286 -0.05969) (xy -0.2286 -0.01651) (xy -0.22606 -0.00508) (xy -0.22479 0.00508) (xy -0.22225 0.01651)
						(xy -0.21971 0.02667) (xy -0.20828 0.05715) (xy -0.19812 0.07747) (xy -0.19177 0.08636) (xy -0.18669 0.09525)
						(xy -0.17907 0.10414) (xy -0.17272 0.11303) (xy -0.1651 0.12065) (xy -0.1651 0.7366) (xy -0.16256 0.76835)
						(xy -0.1524 0.8001) (xy -0.13716 0.82804) (xy -0.11684 0.85344) (xy -0.09144 0.87376) (xy -0.0635 0.889)
						(xy -0.03175 0.89916) (xy 0 0.9017) (xy 0.03175 0.89916) (xy 0.0635 0.889) (xy 0.09144 0.87376)
						(xy 0.11684 0.85344) (xy 0.13716 0.82804) (xy 0.1524 0.8001) (xy 0.16256 0.76835) (xy 0.1651 0.7366)
						(xy 0.1651 0.11938) (xy 0.17272 0.11176) (xy 0.19812 0.0762) (xy 0.2032 0.06604) (xy 0.20701 0.05715)
						(xy 0.21209 0.04699) (xy 0.2159 0.03683) (xy 0.21844 0.02667) (xy 0.22225 0.01524) (xy 0.22352 0.00508)
						(xy 0.22606 -0.00508) (xy 0.22733 -0.01651) (xy 0.22733 -0.02667) (xy 0.2286 -0.0381) (xy 0.22733 -0.04953)
						(xy 0.22733 -0.05969) (xy 0.22606 -0.07112) (xy 0.22352 -0.08128) (xy 0.22225 -0.09144) (xy 0.21844 -0.10287)
						(xy 0.2159 -0.11303) (xy 0.21209 -0.12319) (xy 0.20701 -0.13335) (xy 0.2032 -0.14224) (xy 0.19812 -0.1524)
						(xy 0.17272 -0.18796) (xy 0.1651 -0.19558) (xy 0.1651 -0.7366) (xy 0.16256 -0.76835) (xy 0.1524 -0.8001)
						(xy 0.13716 -0.82804) (xy 0.11684 -0.85344) (xy 0.09144 -0.87376) (xy 0.0635 -0.889) (xy 0.03175 -0.89916)
					)
					(width 0)
					(fill yes)
				)
			)
		)
		(pad "60" smd custom
			(at -13.949934 4.100068)
			(size 0.1143 0.1143)
			(layers "B.Cu" "B.Mask" "B.Paste")
			(net "M_A_DQS_DN3")
			(options
				(clearance outline)
				(anchor circle)
			)
			(primitives
				(gr_poly
					(pts
						(xy 0 -0.9017) (xy -0.03175 -0.89916) (xy -0.0635 -0.889) (xy -0.09144 -0.87376) (xy -0.11684 -0.85344)
						(xy -0.13716 -0.82804) (xy -0.1524 -0.8001) (xy -0.16256 -0.76835) (xy -0.1651 -0.7366) (xy -0.1651 -0.11938)
						(xy -0.17272 -0.11176) (xy -0.19812 -0.0762) (xy -0.2032 -0.06604) (xy -0.20701 -0.05715) (xy -0.21209 -0.04699)
						(xy -0.2159 -0.03683) (xy -0.21844 -0.02667) (xy -0.22225 -0.01524) (xy -0.22352 -0.00508) (xy -0.22606 0.00508)
						(xy -0.22733 0.01651) (xy -0.22733 0.02667) (xy -0.2286 0.0381) (xy -0.22733 0.04953) (xy -0.22733 0.05969)
						(xy -0.22606 0.07112) (xy -0.22352 0.08128) (xy -0.22225 0.09144) (xy -0.21844 0.10287) (xy -0.2159 0.11303)
						(xy -0.21209 0.12319) (xy -0.20701 0.13335) (xy -0.2032 0.14224) (xy -0.19812 0.1524) (xy -0.17272 0.18796)
						(xy -0.1651 0.19558) (xy -0.1651 0.7366) (xy -0.16256 0.76835) (xy -0.1524 0.8001) (xy -0.13716 0.82804)
						(xy -0.11684 0.85344) (xy -0.09144 0.87376) (xy -0.0635 0.889) (xy -0.03175 0.89916) (xy 0 0.9017)
						(xy 0.03175 0.89916) (xy 0.0635 0.889) (xy 0.09144 0.87376) (xy 0.11684 0.85344) (xy 0.13716 0.82804)
						(xy 0.1524 0.8001) (xy 0.16256 0.76835) (xy 0.1651 0.7366) (xy 0.1651 0.19685) (xy 0.17272 0.18923)
						(xy 0.17907 0.18034) (xy 0.18669 0.17145) (xy 0.19177 0.16256) (xy 0.19812 0.15367) (xy 0.20828 0.13335)
						(xy 0.21971 0.10287) (xy 0.22225 0.09271) (xy 0.22479 0.08128) (xy 0.22606 0.07112) (xy 0.2286 0.05969)
						(xy 0.2286 0.01651) (xy 0.22606 0.00508) (xy 0.22479 -0.00508) (xy 0.22225 -0.01651) (xy 0.21971 -0.02667)
						(xy 0.20828 -0.05715) (xy 0.19812 -0.07747) (xy 0.19177 -0.08636) (xy 0.18669 -0.09525) (xy 0.17907 -0.10414)
						(xy 0.17272 -0.11303) (xy 0.1651 -0.12065) (xy 0.1651 -0.7366) (xy 0.16256 -0.76835) (xy 0.1524 -0.8001)
						(xy 0.13716 -0.82804) (xy 0.11684 -0.85344) (xy 0.09144 -0.87376) (xy 0.0635 -0.889) (xy 0.03175 -0.89916)
					)
					(width 0)
					(fill yes)
				)
			)
		)
		(pad "61" smd custom
			(at -13.64996 -4.100068)
			(size 0.1143 0.1143)
			(layers "B.Cu" "B.Mask" "B.Paste")
			(net "GND")
			(options
				(clearance outline)
				(anchor circle)
			)
			(primitives
				(gr_poly
					(pts
						(xy 0 -0.9017) (xy -0.03175 -0.89916) (xy -0.0635 -0.889) (xy -0.09144 -0.87376) (xy -0.11684 -0.85344)
						(xy -0.13716 -0.82804) (xy -0.1524 -0.8001) (xy -0.16256 -0.76835) (xy -0.1651 -0.7366) (xy -0.1651 -0.44958)
						(xy -0.17272 -0.44196) (xy -0.19812 -0.4064) (xy -0.2032 -0.39624) (xy -0.20701 -0.38735) (xy -0.21209 -0.37719)
						(xy -0.2159 -0.36703) (xy -0.21844 -0.35687) (xy -0.22225 -0.34544) (xy -0.22352 -0.33528) (xy -0.22606 -0.32512)
						(xy -0.22733 -0.31369) (xy -0.22733 -0.30353) (xy -0.2286 -0.2921) (xy -0.22733 -0.28067) (xy -0.22733 -0.27051)
						(xy -0.22606 -0.25908) (xy -0.22352 -0.24892) (xy -0.22225 -0.23876) (xy -0.21844 -0.22733) (xy -0.2159 -0.21717)
						(xy -0.21209 -0.20701) (xy -0.20701 -0.19685) (xy -0.2032 -0.18796) (xy -0.19812 -0.1778) (xy -0.17272 -0.14224)
						(xy -0.1651 -0.13462) (xy -0.1651 0.7366) (xy -0.16256 0.76835) (xy -0.1524 0.8001) (xy -0.13716 0.82804)
						(xy -0.11684 0.85344) (xy -0.09144 0.87376) (xy -0.0635 0.889) (xy -0.03175 0.89916) (xy 0 0.9017)
						(xy 0.03175 0.89916) (xy 0.0635 0.889) (xy 0.09144 0.87376) (xy 0.11684 0.85344) (xy 0.13716 0.82804)
						(xy 0.1524 0.8001) (xy 0.16256 0.76835) (xy 0.1651 0.7366) (xy 0.1651 -0.13462) (xy 0.17272 -0.14224)
						(xy 0.19812 -0.1778) (xy 0.2032 -0.18796) (xy 0.20701 -0.19685) (xy 0.21209 -0.20701) (xy 0.2159 -0.21717)
						(xy 0.21844 -0.22733) (xy 0.22225 -0.23876) (xy 0.22352 -0.24892) (xy 0.22606 -0.25908) (xy 0.22733 -0.27051)
						(xy 0.22733 -0.28067) (xy 0.2286 -0.2921) (xy 0.22733 -0.30353) (xy 0.22733 -0.31369) (xy 0.22606 -0.32512)
						(xy 0.22352 -0.33528) (xy 0.22225 -0.34544) (xy 0.21844 -0.35687) (xy 0.2159 -0.36703) (xy 0.21209 -0.37719)
						(xy 0.20701 -0.38735) (xy 0.2032 -0.39624) (xy 0.19812 -0.4064) (xy 0.17272 -0.44196) (xy 0.1651 -0.44958)
						(xy 0.1651 -0.7366) (xy 0.16256 -0.76835) (xy 0.1524 -0.8001) (xy 0.13716 -0.82804) (xy 0.11684 -0.85344)
						(xy 0.09144 -0.87376) (xy 0.0635 -0.889) (xy 0.03175 -0.89916)
					)
					(width 0)
					(fill yes)
				)
			)
		)
		(pad "62" smd custom
			(at -13.349986 4.100068)
			(size 0.1143 0.1143)
			(layers "B.Cu" "B.Mask" "B.Paste")
			(net "M_A_DQS_DP3")
			(options
				(clearance outline)
				(anchor circle)
			)
			(primitives
				(gr_poly
					(pts
						(xy 0 -0.9017) (xy -0.03175 -0.89916) (xy -0.0635 -0.889) (xy -0.09144 -0.87376) (xy -0.11684 -0.85344)
						(xy -0.13716 -0.82804) (xy -0.1524 -0.8001) (xy -0.16256 -0.76835) (xy -0.1651 -0.7366) (xy -0.1651 0.13462)
						(xy -0.17272 0.14224) (xy -0.19812 0.1778) (xy -0.2032 0.18796) (xy -0.20701 0.19685) (xy -0.21209 0.20701)
						(xy -0.2159 0.21717) (xy -0.21844 0.22733) (xy -0.22225 0.23876) (xy -0.22352 0.24892) (xy -0.22606 0.25908)
						(xy -0.22733 0.27051) (xy -0.22733 0.28067) (xy -0.2286 0.2921) (xy -0.22733 0.30353) (xy -0.22733 0.31369)
						(xy -0.22606 0.32512) (xy -0.22352 0.33528) (xy -0.22225 0.34544) (xy -0.21844 0.35687) (xy -0.2159 0.36703)
						(xy -0.21209 0.37719) (xy -0.20701 0.38735) (xy -0.2032 0.39624) (xy -0.19812 0.4064) (xy -0.17272 0.44196)
						(xy -0.1651 0.44958) (xy -0.1651 0.7366) (xy -0.16256 0.76835) (xy -0.1524 0.8001) (xy -0.13716 0.82804)
						(xy -0.11684 0.85344) (xy -0.09144 0.87376) (xy -0.0635 0.889) (xy -0.03175 0.89916) (xy 0 0.9017)
						(xy 0.03175 0.89916) (xy 0.0635 0.889) (xy 0.09144 0.87376) (xy 0.11684 0.85344) (xy 0.13716 0.82804)
						(xy 0.1524 0.8001) (xy 0.16256 0.76835) (xy 0.1651 0.7366) (xy 0.1651 0.44958) (xy 0.17272 0.44196)
						(xy 0.19812 0.4064) (xy 0.2032 0.39624) (xy 0.20701 0.38735) (xy 0.21209 0.37719) (xy 0.2159 0.36703)
						(xy 0.21844 0.35687) (xy 0.22225 0.34544) (xy 0.22352 0.33528) (xy 0.22606 0.32512) (xy 0.22733 0.31369)
						(xy 0.22733 0.30353) (xy 0.2286 0.2921) (xy 0.22733 0.28067) (xy 0.22733 0.27051) (xy 0.22606 0.25908)
						(xy 0.22352 0.24892) (xy 0.22225 0.23876) (xy 0.21844 0.22733) (xy 0.2159 0.21717) (xy 0.21209 0.20701)
						(xy 0.20701 0.19685) (xy 0.2032 0.18796) (xy 0.19812 0.1778) (xy 0.17272 0.14224) (xy 0.1651 0.13462)
						(xy 0.1651 -0.7366) (xy 0.16256 -0.76835) (xy 0.1524 -0.8001) (xy 0.13716 -0.82804) (xy 0.11684 -0.85344)
						(xy 0.09144 -0.87376) (xy 0.0635 -0.889) (xy 0.03175 -0.89916)
					)
					(width 0)
					(fill yes)
				)
			)
		)
	)
)
